# S9S_MB_2U (Grand Teton) — schematic netlist excerpt (pin names and nets, part order shuffled) for the footprints in the layout excerpt that follows; sources: Cadence DE-HDL packaged netlist, KiCad conversion of 03242023_DA0F0TMBIJ0_F0T_Motherboard_J_brd_V01_OCP.brd

PR137  Q_RES  0 5% CHIP  pkg 0402LF  page 270 : A = PVCCIN_CPU0_VOS7 ; B = PVCCIN_CPU0
R734  Q_RES  4.75K 1% CHIP  pkg 0402LF  page 208 : A = CLK_CK440_SMB_ADDR1 ; B = GND

(kicad_pcb
	(version 20260206)
	(generator "pcbnew")
	(generator_version "10.0")
	(general
		(thickness 1.6)
		(legacy_teardrops no)
	)
	(paper "A4")
	(title_block
		(title "03242023_DA0F0TMBIJ0_F0T_Motherboard_J_brd_V01_OCP.brd")
		(comment 1 "Grand Teton / footprints 6044-6045 of 6105")
	)
	(layers
		(0 "F.Cu" signal "TOP")
		(4 "In1.Cu" signal "GND")
		(6 "In2.Cu" signal "IN1")
		(8 "In3.Cu" signal "GND1")
		(10 "In4.Cu" signal "IN2")
		(12 "In5.Cu" signal "GND2")
		(14 "In6.Cu" signal "IN3")
		(16 "In7.Cu" signal "GND3")
		(18 "In8.Cu" signal "VCC")
		(20 "In9.Cu" signal "VCC1")
		(22 "In10.Cu" signal "GND4")
		(24 "In11.Cu" signal "IN4")
		(26 "In12.Cu" signal "GND5")
		(28 "In13.Cu" signal "IN5")
		(30 "In14.Cu" signal "GND6")
		(32 "In15.Cu" signal "IN6")
		(34 "In16.Cu" signal "GND7")
		(2 "B.Cu" signal "BOTTOM")
		(9 "F.Adhes" user "F.Adhesive")
		(11 "B.Adhes" user "B.Adhesive")
		(13 "F.Paste" user "Package Geometry/Pastemask Top")
		(15 "B.Paste" user "Package Geometry/Pastemask Bottom")
		(5 "F.SilkS" user "Ref Des/Silkscreen Top")
		(7 "B.SilkS" user "Ref Des/Silkscreen Bottom")
		(1 "F.Mask" user "Board Geometry/Soldermask Top")
		(3 "B.Mask" user "Board Geometry/Soldermask Bottom")
		(17 "Dwgs.User" user "User.Drawings")
		(19 "Cmts.User" user "User.Comments")
		(21 "Eco1.User" user "User.Eco1")
		(23 "Eco2.User" user "User.Eco2")
		(25 "Edge.Cuts" user "Board Geometry/Outline")
		(27 "Margin" user)
		(31 "F.CrtYd" user "Package Geometry/Place Bound Top")
		(29 "B.CrtYd" user "Package Geometry/Place Bound Bottom")
		(35 "F.Fab" user "Ref Des/Assembly Top")
		(33 "B.Fab" user "Ref Des/Assembly Bottom")
	)
	(footprint ""
		(layer "B.Cu")
		(at 325.168768 -345.774264 -90)
		(property "Reference" "PR137"
			(at 0 0 90)
			(layer "B.SilkS")
			(hide yes)
			(effects
				(font
					(size 1.27 1.27)
				)
				(justify mirror)
			)
		)
		(property "Value" ""
			(at 0 0 90)
			(layer "B.Fab")
			(effects
				(font
					(size 1.27 1.27)
				)
				(justify mirror)
			)
		)
		(duplicate_pad_numbers_are_jumpers no)
		(fp_line
			(start -0.7874 0.4064)
			(end 0.7874 0.4064)
			(stroke
				(width 0.1524)
				(type default)
			)
			(layer "B.SilkS")
		)
		(fp_line
			(start 0.7874 0.4064)
			(end 0.7874 -0.4064)
			(stroke
				(width 0.1524)
				(type default)
			)
			(layer "B.SilkS")
		)
		(fp_line
			(start -0.7874 -0.4064)
			(end -0.7874 0.4064)
			(stroke
				(width 0.1524)
				(type default)
			)
			(layer "B.SilkS")
		)
		(fp_line
			(start 0.7874 -0.4064)
			(end -0.7874 -0.4064)
			(stroke
				(width 0.1524)
				(type default)
			)
			(layer "B.SilkS")
		)
		(fp_line
			(start -0.67945 0.3048)
			(end -0.120396 0.3048)
			(stroke
				(width 0.1)
				(type default)
			)
			(layer "B.Fab")
		)
		(fp_line
			(start -0.120396 0.3048)
			(end -0.120396 0.2794)
			(stroke
				(width 0.1)
				(type default)
			)
			(layer "B.Fab")
		)
		(fp_line
			(start 0.12065 0.3048)
			(end 0.67945 0.3048)
			(stroke
				(width 0.1)
				(type default)
			)
			(layer "B.Fab")
		)
		(fp_line
			(start 0.67945 0.3048)
			(end 0.67945 -0.305054)
			(stroke
				(width 0.1)
				(type default)
			)
			(layer "B.Fab")
		)
		(fp_line
			(start -0.120396 0.2794)
			(end 0.12065 0.2794)
			(stroke
				(width 0.1)
				(type default)
			)
			(layer "B.Fab")
		)
		(fp_line
			(start 0.12065 0.2794)
			(end 0.12065 0.3048)
			(stroke
				(width 0.1)
				(type default)
			)
			(layer "B.Fab")
		)
		(fp_line
			(start -0.12065 -0.2794)
			(end -0.12065 -0.3048)
			(stroke
				(width 0.1)
				(type default)
			)
			(layer "B.Fab")
		)
		(fp_line
			(start 0.12065 -0.2794)
			(end -0.12065 -0.2794)
			(stroke
				(width 0.1)
				(type default)
			)
			(layer "B.Fab")
		)
		(fp_line
			(start -0.67945 -0.3048)
			(end -0.67945 0.3048)
			(stroke
				(width 0.1)
				(type default)
			)
			(layer "B.Fab")
		)
		(fp_line
			(start -0.12065 -0.3048)
			(end -0.67945 -0.3048)
			(stroke
				(width 0.1)
				(type default)
			)
			(layer "B.Fab")
		)
		(fp_line
			(start 0.12065 -0.305054)
			(end 0.12065 -0.2794)
			(stroke
				(width 0.1)
				(type default)
			)
			(layer "B.Fab")
		)
		(fp_line
			(start 0.67945 -0.305054)
			(end 0.12065 -0.305054)
			(stroke
				(width 0.1)
				(type default)
			)
			(layer "B.Fab")
		)
		(pad "1" smd circle
			(at 0.40005 0 90)
			(size 0 0)
			(layers "B.Cu" "B.Mask" "B.Paste")
			(net "PVCCIN_CPU0_VOS7")
		)
		(pad "2" smd circle
			(at -0.40005 0 90)
			(size 0 0)
			(layers "B.Cu" "B.Mask" "B.Paste")
			(net "PVCCIN_CPU0")
		)
	)
	(footprint ""
		(layer "B.Cu")
		(at 245.835424 -100.121212)
		(property "Reference" "R734"
			(at 0 0 0)
			(layer "B.SilkS")
			(hide yes)
			(effects
				(font
					(size 1.27 1.27)
				)
				(justify mirror)
			)
		)
		(property "Value" ""
			(at 0 0 0)
			(layer "B.Fab")
			(effects
				(font
					(size 1.27 1.27)
				)
				(justify mirror)
			)
		)
		(duplicate_pad_numbers_are_jumpers no)
		(fp_line
			(start -0.7874 -0.4064)
			(end -0.7874 0.4064)
			(stroke
				(width 0.1524)
				(type default)
			)
			(layer "B.SilkS")
		)
		(fp_line
			(start -0.7874 0.4064)
			(end 0.7874 0.4064)
			(stroke
				(width 0.1524)
				(type default)
			)
			(layer "B.SilkS")
		)
		(fp_line
			(start 0.7874 -0.4064)
			(end -0.7874 -0.4064)
			(stroke
				(width 0.1524)
				(type default)
			)
			(layer "B.SilkS")
		)
		(fp_line
			(start 0.7874 0.4064)
			(end 0.7874 -0.4064)
			(stroke
				(width 0.1524)
				(type default)
			)
			(layer "B.SilkS")
		)
		(fp_line
			(start -0.67945 -0.3048)
			(end -0.67945 0.3048)
			(stroke
				(width 0.1)
				(type default)
			)
			(layer "B.Fab")
		)
		(fp_line
			(start -0.67945 0.3048)
			(end -0.120396 0.3048)
			(stroke
				(width 0.1)
				(type default)
			)
			(layer "B.Fab")
		)
		(fp_line
			(start -0.12065 -0.3048)
			(end -0.67945 -0.3048)
			(stroke
				(width 0.1)
				(type default)
			)
			(layer "B.Fab")
		)
		(fp_line
			(start -0.12065 -0.2794)
			(end -0.12065 -0.3048)
			(stroke
				(width 0.1)
				(type default)
			)
			(layer "B.Fab")
		)
		(fp_line
			(start -0.120396 0.2794)
			(end 0.12065 0.2794)
			(stroke
				(width 0.1)
				(type default)
			)
			(layer "B.Fab")
		)
		(fp_line
			(start -0.120396 0.3048)
			(end -0.120396 0.2794)
			(stroke
				(width 0.1)
				(type default)
			)
			(layer "B.Fab")
		)
		(fp_line
			(start 0.12065 -0.305054)
			(end 0.12065 -0.2794)
			(stroke
				(width 0.1)
				(type default)
			)
			(layer "B.Fab")
		)
		(fp_line
			(start 0.12065 -0.2794)
			(end -0.12065 -0.2794)
			(stroke
				(width 0.1)
				(type default)
			)
			(layer "B.Fab")
		)
		(fp_line
			(start 0.12065 0.2794)
			(end 0.12065 0.3048)
			(stroke
				(width 0.1)
				(type default)
			)
			(layer "B.Fab")
		)
		(fp_line
			(start 0.12065 0.3048)
			(end 0.67945 0.3048)
			(stroke
				(width 0.1)
				(type default)
			)
			(layer "B.Fab")
		)
		(fp_line
			(start 0.67945 -0.305054)
			(end 0.12065 -0.305054)
			(stroke
				(width 0.1)
				(type default)
			)
			(layer "B.Fab")
		)
		(fp_line
			(start 0.67945 0.3048)
			(end 0.67945 -0.305054)
			(stroke
				(width 0.1)
				(type default)
			)
			(layer "B.Fab")
		)
		(pad "1" smd circle
			(at 0.40005 0 180)
			(size 0 0)
			(layers "B.Cu" "B.Mask" "B.Paste")
			(net "CLK_CK440_SMB_ADDR1")
		)
		(pad "2" smd circle
			(at -0.40005 0 180)
			(size 0 0)
			(layers "B.Cu" "B.Mask" "B.Paste")
			(net "GND")
		)
	)
)
